FILE_TYPE = CONNECTIVITY;
{Allegro Design Entry HDL 17.4-2019 S026 (4007227) 1/17/2022}
"PAGE_NUMBER" = 149;
0"NC";
1"GND\g";
2"GND\g";
3"GND\g";
4"GND\g";
5"GND\g";
6"GND\g";
7"PVDD18_S5_P0\g";
8"GND\g";
9"GND\g";
10"GND\g";
11"GND\g";
12"GND\g";
13"GND\g";
14"GND\g";
15"GND\g";
16"GND\g";
17"GND\g";
18"PVDD18_S5_P0\g";
19"GND\g";
20"GND\g";
21"P3V3_AUX\g";
22"GND\g";
23"JTAG_TDI";
24"CPU0_HDT_CONN_TESTEN";
25"PVDD18_S5_P0\g";
26"PVDD18_S5_P0\g";
27"GND\g";
28"PVDD18_S5_P0\g";
29"PVDD18_S5_P0\g";
30"GND\g";
31"PVDD18_S5_P0\g";
32"P3V3_AUX\g";
33"GND\g";
34"PVDD18_S5_P0\g";
35"PVDD18_S5_P0\g";
36"GND\g";
37"P3V3_AUX\g";
38"GND\g";
39"HDT_HDR_TDI";
40"HDT_HDR_PWROK";
41"HDT_HDR_RESET_N";
42"HDT_HDR_DBREQ_N";
43"HDT_HDR_TDO";
44"HDT_HDR_TMS";
45"JTAG_TCK_R";
46"JTAG_TCK";
47"JTAG_TMS_R";
48"JTAG_TMS";
49"HDT_HDR_TCK";
50"HDT_HDR_TRST_N";
51"HDT_HDR_TMS";
52"HDT_HDR_DBREQ_N";
53"JTAG_SCM_MUX_TMS";
54"JTAG_SCM_TRST_N";
55"JTAG_SCM_DBREQ_N";
56"JTAG_SCM_MUX_TCK";
57"HDT_HDR_TDI";
58"HDT_HDR_R_TDI";
59"HDT_HDR_R_TMS";
60"HDT_HDR_R_TCK";
61"HDT_HDR_TDO_R";
62"JTAG_TDO";
63"HDT_HDR_TCK";
64"HDT_HDR_DBREQ_R_N";
65"HDT_CPU0_HDT_CONN_TESTEN";
66"HDT_CPU0_XTRIG_L7";
67"CPU0_XTRIG_L7";
68"HDT_CPU0_XTRIG_L6";
69"CPU0_XTRIG_L6";
70"HDT_HDR_TRST_N_R";
71"HDT_HDR_TRST_N";
72"HDT_CPU0_XTRIG_L5";
73"CPU0_XTRIG_L5";
74"PRSNT_HDT_R_N";
75"PRSNT_HDT_N";
76"JTAG_TRST_N";
77"JTAG_TRST_R_N";
78"JTAG_DBREQ_N";
79"JTAG_DBREQ_R_N";
80"HDT_HDR_TDO";
81"JTAG_SCM_MUX_TDO";
82"JTAG_SCM_MUX_TDI";
83"JTAG_BMC_OE_N";
84"JTAG_TDO_R1";
85"JTAG_TDI_R";
86"JTAG_BMC_OE";
87"JTAG_BMC_R_D_OE";
%"SN74AVC2T245RSWR"
"1","(-7000,2100)","2","pure_quanta","I1";
;
LOCATION"U147"
$SEC"1"
CDS_SEC"1"
MATERIAL"IC"
PART_TYPE"SMLF"
VALUE"SN74AVC2T245RSWR"
NEEDS_NO_SIZE"TRUE"
CDS_LIB"pure_quanta"
CDS_LMAN_SYM_OUTLINE"-250,375,250,-375"
PART_NUMBER"AL02T245000";
"DIR1"
$PN"10"37;
"A2"
$PN"9"82;
"A1"
$PN"8"81;
"VCCA"
$PN"7"37;
"VCCB"
$PN"6"35;
"B1"
$PN"5"85;
"B2"
$PN"4"84;
"GND"
$PN"3"38;
"OE_# \B"
$PN"2"83;
"DIR2"
$PN"1"38;
%"Q_CAP"
"1","(-2650,4550)","0","pure_quanta","I10";
;
LOCATION"C1509"
$SEC"1"
CDS_SEC"1"
PACK_TYPE"C0402"
VOLTAGE"16V"
VALUE"0.1UF"
TOLERANCE"10%"
MATERIAL"X7R"
CDS_LIB"pure_quanta"
PART_NUMBER"CH4103K1B08";
"B"
$PN"2"1;
"A"
$PN"1"26;
%"Q_RES"
"2","(-6425,3550)","0","pure_quanta","I101";
;
LOCATION"R617"
$SEC"1"
CDS_SEC"1"
MATERIAL"CHIP"
WATTAGE"1/16W"
TOLERANCE"5%"
VALUE"4.7K"
PACK_TYPE"0402LF"
CDS_LIB"pure_quanta"
PART_NUMBER"CS24702JB10";
"A"
$PN"1"18;
"B"
$PN"2"87;
%"MOSFET_N"
"1","(-7525,700)","0","pure_quanta","I102";
;
LOCATION"Q62"
$SEC"1"
CDS_SEC"1"
PART_TYPE"SMLF"
MATERIAL"IC"
VALUE"BSS138K"
PACK_TYPE"SMLF"
CDS_LMAN_SYM_OUTLINE"-50,50,100,-150"
CDS_LIB"pure_quanta"
MANUF_PN"BSS138K"
PART_NUMBER"BAM138K0000";
"GATE"
$PN"G"86;
"SOURCE"
$PN"S"22;
"DRAIN"
$PN"D"83;
%"Q_RES"
"1","(-3975,5850)","0","pure_quanta","I109";
;
LOCATION"R1354"
$SEC"1"
CDS_SEC"1"
VALUE"0"
CDS_LIB"pure_quanta"
WATTAGE"1/16W"
MATERIAL"CHIP"
TOLERANCE"5%"
PACK_TYPE"0402LF"
PART_NUMBER"CS00002JB13";
"B"
$PN"2"39;
"A"
$PN"1"58;
%"GND"
"1","(-2650,4375)","0","pure_quanta_power","I11";
;
SIZE"1B"
CDS_LIB"pure_quanta_power"
HDL_POWER"GND";
"A<SIZE-1..0>\NAC"1;
%"GND"
"1","(-3675,5100)","0","pure_quanta_power","I110";
;
CDS_LIB"pure_quanta_power"
SIZE"1B"
HDL_POWER"GND";
"A<SIZE-1..0>\NAC"2;
%"Q_RES"
"2","(-3650,6125)","0","pure_quanta","I111";
;
LOCATION"R1624"
$SEC"1"
CDS_SEC"1"
VALUE"1K"
TOLERANCE"1%"
CDS_LIB"pure_quanta"
WATTAGE"1/16W"
MATERIAL"CHIP"
PACK_TYPE"0402LF"
PART_NUMBER"CS21002FB06";
"A"
$PN"1"25;
"B"
$PN"2"63;
%"Q_RES"
"2","(-3675,5325)","0","pure_quanta","I112";
;
LOCATION"R1629"
$SEC"1"
CDS_SEC"1"
WATTAGE"1/16W"
MATERIAL"CHIP"
VALUE"1K"
PACK_TYPE"0402LF"
TOLERANCE"1%"
CDS_LIB"pure_quanta"
PART_NUMBER"CS21002FB06";
"A"
$PN"1"65;
"B"
$PN"2"2;
%"Q_RES"
"1","(-3025,5600)","0","pure_quanta","I113";
;
LOCATION"R1631"
$SEC"1"
CDS_SEC"1"
VALUE"33"
CDS_LIB"pure_quanta"
WATTAGE"1/16W"
MATERIAL"CHIP"
TOLERANCE"5%"
PACK_TYPE"0402LF"
PART_NUMBER"CS03302JB10";
"B"
$PN"2"42;
"A"
$PN"1"64;
%"Q_RES"
"1","(-3025,5550)","0","pure_quanta","I114";
;
LOCATION"R1632"
$SEC"1"
CDS_SEC"1"
VALUE"33"
CDS_LIB"pure_quanta"
WATTAGE"1/16W"
MATERIAL"CHIP"
TOLERANCE"5%"
PACK_TYPE"0402LF"
PART_NUMBER"CS03302JB10";
"B"
$PN"2"24;
"A"
$PN"1"65;
%"Q_RES"
"2","(-3525,6125)","0","pure_quanta","I115";
;
LOCATION"R1626"
$SEC"1"
CDS_SEC"1"
VALUE"1K"
TOLERANCE"1%"
CDS_LIB"pure_quanta"
WATTAGE"1/16W"
MATERIAL"CHIP"
PACK_TYPE"0402LF"
PART_NUMBER"CS21002FB06";
"A"
$PN"1"25;
"B"
$PN"2"44;
%"Q_RES"
"2","(-3400,6125)","0","pure_quanta","I116";
;
LOCATION"R1627"
$SEC"1"
CDS_SEC"1"
VALUE"1K"
TOLERANCE"1%"
CDS_LIB"pure_quanta"
WATTAGE"1/16W"
MATERIAL"CHIP"
PACK_TYPE"0402LF"
PART_NUMBER"CS21002FB06";
"A"
$PN"1"25;
"B"
$PN"2"39;
%"Q_RES"
"2","(-3275,6125)","0","pure_quanta","I117";
;
LOCATION"R1628"
$SEC"1"
CDS_SEC"1"
VALUE"1K"
TOLERANCE"1%"
CDS_LIB"pure_quanta"
WATTAGE"1/16W"
MATERIAL"CHIP"
PACK_TYPE"0402LF"
PART_NUMBER"CS21002FB06";
"A"
$PN"1"25;
"B"
$PN"2"43;
%"Q_RES"
"2","(-3150,6125)","0","pure_quanta","I118";
;
LOCATION"R1630"
$SEC"1"
CDS_SEC"1"
VALUE"1K"
TOLERANCE"1%"
CDS_LIB"pure_quanta"
WATTAGE"1/16W"
MATERIAL"CHIP"
PACK_TYPE"0402LF"
PART_NUMBER"CS21002FB06";
"A"
$PN"1"25;
"B"
$PN"2"64;
%"UNIVERSAL_POWER"
"1","(-3650,6400)","0","pure_quanta_power","I119";
;
HDL_POWER"PVDD18_S5_P0"
CDS_LIB"pure_quanta_power";
"A"25;
%"UNIVERSAL_POWER"
"1","(-2725,4850)","0","pure_quanta_power","I12";
;
HDL_POWER"PVDD18_S5_P0"
CDS_LIB"pure_quanta_power";
"A"26;
%"GND"
"1","(-2350,5100)","0","pure_quanta_power","I120";
;
CDS_LIB"pure_quanta_power"
SIZE"1B"
HDL_POWER"GND";
"A<SIZE-1..0>\NAC"3;
%"GND"
"1","(-2125,5100)","0","pure_quanta_power","I121";
;
SIZE"1B"
CDS_LIB"pure_quanta_power"
HDL_POWER"GND";
"A<SIZE-1..0>\NAC"4;
%"Q_CAP"
"1","(-2125,5325)","0","pure_quanta","I123";
;
LOCATION"C551"
$SEC"1"
CDS_SEC"1"
VALUE"0.01UF"
VOLTAGE"50V"
TOLERANCE"10%"
PACK_TYPE"C0402"
MATERIAL"X7R"
CDS_LIB"pure_quanta"
SIGNAL_MODEL"DEFAULT_CAPACITOR_10000PF_2_1"
PART_NUMBER"CH31006KB18";
"B"
$PN"2"4;
"A"
$PN"1"24;
%"Q_RES"
"1","(-3975,5950)","0","pure_quanta","I132";
;
LOCATION"R1352"
$SEC"1"
CDS_SEC"1"
VALUE"0"
CDS_LIB"pure_quanta"
WATTAGE"1/16W"
MATERIAL"CHIP"
TOLERANCE"5%"
PACK_TYPE"0402LF"
PART_NUMBER"CS00002JB13";
"B"
$PN"2"63;
"A"
$PN"1"60;
%"Q_RES"
"1","(-3975,5900)","0","pure_quanta","I133";
;
LOCATION"R1353"
$SEC"1"
CDS_SEC"1"
VALUE"0"
CDS_LIB"pure_quanta"
WATTAGE"1/16W"
MATERIAL"CHIP"
TOLERANCE"5%"
PACK_TYPE"0402LF"
PART_NUMBER"CS00002JB13";
"B"
$PN"2"44;
"A"
$PN"1"59;
%"Q_CAP"
"1","(-2350,5325)","0","pure_quanta","I134";
;
LOCATION"C87"
$SEC"1"
CDS_SEC"1"
VALUE"0.001UF"
TOLERANCE"10%"
PACK_TYPE"C0402"
VOLTAGE"50V"
MATERIAL"X7R"
CDS_LIB"pure_quanta"
PART_NUMBER"CH30106KB19";
"B"
$PN"2"3;
"A"
$PN"1"42;
%"Q_CAP"
"1","(-2575,5325)","0","pure_quanta","I137";
;
LOCATION"C605"
$SEC"1"
CDS_SEC"1"
VALUE"0.001UF"
PACK_TYPE"C0402"
VOLTAGE"50V"
TOLERANCE"10%"
MATERIAL"X7R"
CDS_LIB"pure_quanta"
PART_NUMBER"CH30106KB19";
"B"
$PN"2"5;
"A"
$PN"1"39;
%"GND"
"1","(-2575,5100)","0","pure_quanta_power","I138";
;
CDS_LIB"pure_quanta_power"
SIZE"1B"
HDL_POWER"GND";
"A<SIZE-1..0>\NAC"5;
%"Q_CAP"
"1","(-2800,5325)","0","pure_quanta","I140";
;
LOCATION"C604"
$SEC"1"
CDS_SEC"1"
VALUE"0.001UF"
PACK_TYPE"C0402"
VOLTAGE"50V"
TOLERANCE"10%"
MATERIAL"X7R"
CDS_LIB"pure_quanta"
PART_NUMBER"CH30106KB19";
"B"
$PN"2"6;
"A"
$PN"1"63;
%"GND"
"1","(-2800,5100)","0","pure_quanta_power","I141";
;
CDS_LIB"pure_quanta_power"
SIZE"1B"
HDL_POWER"GND";
"A<SIZE-1..0>\NAC"6;
%"SCONN20_HSU2101L00007H"
"1","(-5125,5725)","0","pure_quanta","I142";
;
LOCATION"J54"
$SEC"1"
CDS_SEC"1"
VALUE"SCONN20_HSU2101-L0000-7H"
MATERIAL"IO"
PART_TYPE"SMLF"
CDS_LMAN_SYM_OUTLINE"-100,275,100,-275"
NEEDS_NO_SIZE"TRUE"
CDS_LIB"pure_quanta"
PART_NUMBER"DFHD20MS153";
"20"
$PN"20"0;
"19"
$PN"19"28;
"18"
$PN"18"65;
"17"
$PN"17"27;
"16"
$PN"16"64;
"15"
$PN"15"72;
"14"
$PN"14"0;
"13"
$PN"13"66;
"12"
$PN"12"41;
"11"
$PN"11"68;
"10"
$PN"10"40;
"9"
$PN"9"70;
"8"
$PN"8"43;
"7"
$PN"7"27;
"6"
$PN"6"58;
"5"
$PN"5"27;
"4"
$PN"4"59;
"3"
$PN"3"74;
"2"
$PN"2"60;
"1"
$PN"1"28;
%"GND"
"1","(-5475,5350)","0","pure_quanta_power","I143";
;
SIZE"1B"
CDS_LIB"pure_quanta_power"
HDL_POWER"GND";
"A<SIZE-1..0>\NAC"27;
%"UNIVERSAL_POWER"
"1","(-5600,6200)","0","pure_quanta_power","I144";
;
HDL_POWER"PVDD18_S5_P0"
CDS_LIB"pure_quanta_power";
"A"28;
%"UNIVERSAL_POWER"
"1","(-6050,6450)","0","pure_quanta_power","I145";
;
HDL_POWER"PVDD18_S5_P0"
CDS_LIB"pure_quanta_power";
"A"7;
%"Q_RES"
"2","(-6050,6250)","0","pure_quanta","I146";
;
LOCATION"R1621"
$SEC"1"
CDS_SEC"1"
WATTAGE"1/16W"
MATERIAL"CHIP"
VALUE"1K"
PACK_TYPE"0402LF"
TOLERANCE"1%"
CDS_LIB"pure_quanta"
PART_NUMBER"CS21002FB06";
"A"
$PN"1"7;
"B"
$PN"2"70;
%"Q_RES"
"1","(-6300,5650)","0","pure_quanta","I147";
;
LOCATION"R477"
$SEC"1"
CDS_SEC"1"
VALUE"33"
CDS_LIB"pure_quanta"
WATTAGE"1/16W"
MATERIAL"CHIP"
TOLERANCE"5%"
PACK_TYPE"0402LF"
PART_NUMBER"CS03302JB10";
"B"
$PN"2"66;
"A"
$PN"1"67;
%"Q_RES"
"1","(-6300,5700)","0","pure_quanta","I148";
;
LOCATION"R476"
$SEC"1"
CDS_SEC"1"
VALUE"33"
CDS_LIB"pure_quanta"
WATTAGE"1/16W"
MATERIAL"CHIP"
TOLERANCE"5%"
PACK_TYPE"0402LF"
PART_NUMBER"CS03302JB10";
"B"
$PN"2"68;
"A"
$PN"1"69;
%"Q_RES"
"1","(-6300,5750)","0","pure_quanta","I149";
;
LOCATION"R1620"
$SEC"1"
CDS_SEC"1"
VALUE"33"
CDS_LIB"pure_quanta"
WATTAGE"1/16W"
MATERIAL"CHIP"
TOLERANCE"5%"
PACK_TYPE"0402LF"
PART_NUMBER"CS03302JB10";
"B"
$PN"2"70;
"A"
$PN"1"71;
%"Q_RES"
"1","(-6300,5600)","0","pure_quanta","I150";
;
LOCATION"R478"
$SEC"1"
CDS_SEC"1"
VALUE"33"
CDS_LIB"pure_quanta"
WATTAGE"1/16W"
MATERIAL"CHIP"
TOLERANCE"5%"
PACK_TYPE"0402LF"
PART_NUMBER"CS03302JB10";
"B"
$PN"2"72;
"A"
$PN"1"73;
%"GND"
"1","(-7000,5150)","0","pure_quanta_power","I151";
;
CDS_LIB"pure_quanta_power"
SIZE"1B"
HDL_POWER"GND";
"A<SIZE-1..0>\NAC"8;
%"Q_CAP"
"1","(-7000,5375)","0","pure_quanta","I152";
;
LOCATION"C85"
$SEC"1"
CDS_SEC"1"
PACK_TYPE"C0402"
VOLTAGE"50V"
VALUE"0.001UF"
TOLERANCE"10%"
MATERIAL"X7R"
CDS_LIB"pure_quanta"
PART_NUMBER"CH30106KB19";
"B"
$PN"2"8;
"A"
$PN"1"71;
%"Q_RES"
"1","(-6300,5900)","0","pure_quanta","I157";
;
LOCATION"R1528"
$SEC"1"
CDS_SEC"1"
VALUE"33"
CDS_LIB"pure_quanta"
WATTAGE"1/16W"
MATERIAL"CHIP"
TOLERANCE"5%"
PACK_TYPE"0402LF"
PART_NUMBER"CS03302JB10";
"B"
$PN"2"74;
"A"
$PN"1"75;
%"Q_RES"
"1","(-8400,3975)","0","pure_quanta","I159";
;
LOCATION"R6108"
$SEC"1"
CDS_SEC"1"
VALUE"0"
MATERIAL"CHIP"
CDS_LIB"pure_quanta"
PACK_TYPE"0402LF"
TOLERANCE"5%"
WATTAGE"1/16W"
PART_NUMBER"CS00002JB13";
"B"
$PN"2"61;
"A"
$PN"1"80;
%"Q_RES"
"1","(-5675,3925)","0","pure_quanta","I160";
;
LOCATION"R6111"
$SEC"1"
CDS_SEC"1"
VALUE"0"
PACK_TYPE"0402LF"
TOLERANCE"5%"
MATERIAL"CHIP"
WATTAGE"1/16W"
CDS_LIB"pure_quanta"
PART_NUMBER"CS00002JB13";
"B"
$PN"2"62;
"A"
$PN"1"84;
%"Q_CAP"
"1","(-5125,4425)","0","pure_quanta","I161";
;
LOCATION"C86"
$SEC"1"
CDS_SEC"1"
PACK_TYPE"C0402"
MATERIAL"EMPTY"
TOLERANCE"10%"
VOLTAGE"50V"
VALUE"0.01UF"
CDS_LIB"pure_quanta"
PART_NUMBER"CH31006KB18";
"B"
$PN"2"9;
"A"
$PN"1"23;
%"GND"
"1","(-5125,4200)","0","pure_quanta_power","I162";
;
SIZE"1B"
CDS_LIB"pure_quanta_power"
HDL_POWER"GND";
"A<SIZE-1..0>\NAC"9;
%"Q_CAP"
"1","(-8075,3150)","2","pure_quanta","I163";
;
LOCATION"C8006"
$SEC"1"
CDS_SEC"1"
VALUE"0.1UF"
PACK_TYPE"0402"
TOLERANCE"10%"
MATERIAL"X7R"
VOLTAGE"25V"
CDS_LIB"pure_quanta"
PART_NUMBER"CH4104K1B00";
"B"
$PN"2"10;
"A"
$PN"1"87;
%"GND"
"1","(-8075,2925)","0","pure_quanta_power","I164";
;
SIZE"1B"
CDS_LIB"pure_quanta_power"
HDL_POWER"GND";
"A<SIZE-1..0>\NAC"10;
%"UNIVERSAL_POWER"
"1","(-3750,4825)","0","pure_quanta_power","I20";
;
HDL_POWER"PVDD18_S5_P0"
CDS_LIB"pure_quanta_power";
"A"29;
%"Q_CAP"
"1","(-800,3775)","0","pure_quanta","I21";
;
LOCATION"C1512"
$SEC"1"
CDS_SEC"1"
PACK_TYPE"0402"
VOLTAGE"50V"
VALUE"33PF"
TOLERANCE"5%"
MATERIAL"NPO"
CDS_LIB"pure_quanta"
PART_NUMBER"TMP_QCH03306JB04";
"B"
$PN"2"11;
"A"
$PN"1"78;
%"GND"
"1","(-800,3450)","0","pure_quanta_power","I22";
;
SIZE"1B"
CDS_LIB"pure_quanta_power"
HDL_POWER"GND";
"A<SIZE-1..0>\NAC"11;
%"Q_CAP"
"1","(-1125,3775)","0","pure_quanta","I23";
;
LOCATION"C1511"
$SEC"1"
CDS_SEC"1"
PACK_TYPE"0402"
VOLTAGE"50V"
VALUE"33PF"
TOLERANCE"5%"
MATERIAL"NPO"
CDS_LIB"pure_quanta"
PART_NUMBER"TMP_QCH03306JB04";
"B"
$PN"2"12;
"A"
$PN"1"76;
%"GND"
"1","(-1125,3450)","0","pure_quanta_power","I24";
;
SIZE"1B"
CDS_LIB"pure_quanta_power"
HDL_POWER"GND";
"A<SIZE-1..0>\NAC"12;
%"Q_CAP"
"1","(-1500,3775)","0","pure_quanta","I25";
;
LOCATION"C1510"
$SEC"1"
CDS_SEC"1"
PACK_TYPE"0402"
VOLTAGE"50V"
VALUE"33PF"
TOLERANCE"5%"
MATERIAL"NPO"
CDS_LIB"pure_quanta"
PART_NUMBER"TMP_QCH03306JB04";
"B"
$PN"2"13;
"A"
$PN"1"46;
%"GND"
"1","(-1500,3450)","0","pure_quanta_power","I26";
;
CDS_LIB"pure_quanta_power"
SIZE"1B"
HDL_POWER"GND";
"A<SIZE-1..0>\NAC"13;
%"GND"
"1","(-2700,3500)","0","pure_quanta_power","I27";
;
SIZE"1B"
CDS_LIB"pure_quanta_power"
HDL_POWER"GND";
"A<SIZE-1..0>\NAC"30;
%"UNIVERSAL_POWER"
"1","(-2725,2950)","0","pure_quanta_power","I28";
;
HDL_POWER"PVDD18_S5_P0"
CDS_LIB"pure_quanta_power";
"A"31;
%"Q_CAP"
"1","(-2650,2650)","0","pure_quanta","I29";
;
LOCATION"C1508"
$SEC"1"
CDS_SEC"1"
PACK_TYPE"C0402"
VOLTAGE"16V"
VALUE"0.1UF"
TOLERANCE"10%"
MATERIAL"X7R"
CDS_LIB"pure_quanta"
PART_NUMBER"CH4103K1B08";
"B"
$PN"2"14;
"A"
$PN"1"31;
%"GND"
"1","(-2650,2475)","0","pure_quanta_power","I30";
;
CDS_LIB"pure_quanta_power"
SIZE"1B"
HDL_POWER"GND";
"A<SIZE-1..0>\NAC"14;
%"SN74AVC4T774PWR"
"1","(-3225,4075)","0","pure_quanta","I31";
;
LOCATION"U149"
$SEC"1"
CDS_SEC"1"
PART_TYPE"SMLF"
VALUE"SN74AVC4T774PWR"
MATERIAL"IC"
CDS_LMAN_SYM_OUTLINE"-250,450,250,-450"
NEEDS_NO_SIZE"TRUE"
CDS_LIB"pure_quanta"
PART_NUMBER"AL04T774K00";
"VCCA"
$PN"16"29;
"VCCB"
$PN"15"26;
"B1"
$PN"14"45;
"B2"
$PN"13"47;
"B3"
$PN"12"77;
"B4"
$PN"11"79;
"GND"
$PN"10"30;
"OE \B"
$PN"9"87;
"DIR4"
$PN"8"29;
"DIR3"
$PN"7"29;
"A4"
$PN"6"52;
"A3"
$PN"5"50;
"A2"
$PN"4"51;
"A1"
$PN"3"49;
"DIR2"
$PN"2"29;
"DIR1"
$PN"1"29;
%"UNIVERSAL_POWER"
"1","(-3750,2675)","0","pure_quanta_power","I32";
;
HDL_POWER"P3V3_AUX"
CDS_LIB"pure_quanta_power";
"A"32;
%"GND"
"1","(-2725,1350)","0","pure_quanta_power","I33";
;
CDS_LIB"pure_quanta_power"
SIZE"1B"
HDL_POWER"GND";
"A<SIZE-1..0>\NAC"33;
%"SN74AVC4T774PWR"
"1","(-3250,1925)","0","pure_quanta","I34";
;
LOCATION"U148"
$SEC"1"
CDS_SEC"1"
VALUE"SN74AVC4T774PWR"
MATERIAL"IC"
PART_TYPE"SMLF"
NEEDS_NO_SIZE"TRUE"
CDS_LIB"pure_quanta"
CDS_LMAN_SYM_OUTLINE"-250,450,250,-450"
PART_NUMBER"AL04T774K00";
"VCCA"
$PN"16"32;
"VCCB"
$PN"15"31;
"B1"
$PN"14"45;
"B2"
$PN"13"47;
"B3"
$PN"12"77;
"B4"
$PN"11"79;
"GND"
$PN"10"33;
"OE \B"
$PN"9"83;
"DIR4"
$PN"8"32;
"DIR3"
$PN"7"32;
"A4"
$PN"6"55;
"A3"
$PN"5"54;
"A2"
$PN"4"53;
"A1"
$PN"3"56;
"DIR2"
$PN"2"32;
"DIR1"
$PN"1"32;
%"Q_CAP"
"1","(-3975,4550)","0","pure_quanta","I41";
;
LOCATION"C1507"
$SEC"1"
CDS_SEC"1"
VALUE"0.1UF"
PACK_TYPE"C0402"
VOLTAGE"16V"
TOLERANCE"10%"
MATERIAL"X7R"
CDS_LIB"pure_quanta"
PART_NUMBER"CH4103K1B08";
"B"
$PN"2"15;
"A"
$PN"1"29;
%"GND"
"1","(-3975,4375)","0","pure_quanta_power","I42";
;
CDS_LIB"pure_quanta_power"
SIZE"1B"
HDL_POWER"GND";
"A<SIZE-1..0>\NAC"15;
%"Q_RES"
"1","(-5675,4075)","0","pure_quanta","I53";
;
LOCATION"R1625"
$SEC"1"
CDS_SEC"1"
VALUE"0"
PACK_TYPE"0402LF"
TOLERANCE"5%"
MATERIAL"CHIP"
WATTAGE"1/16W"
CDS_LIB"pure_quanta"
PART_NUMBER"CS00002JB13";
"B"
$PN"2"23;
"A"
$PN"1"85;
%"UNIVERSAL_POWER"
"1","(-6475,4900)","0","pure_quanta_power","I54";
;
HDL_POWER"PVDD18_S5_P0"
CDS_LIB"pure_quanta_power";
"A"34;
%"GND"
"1","(-6350,4400)","0","pure_quanta_power","I55";
;
CDS_LIB"pure_quanta_power"
SIZE"1B"
HDL_POWER"GND";
"A<SIZE-1..0>\NAC"16;
%"Q_CAP"
"1","(-6350,4625)","0","pure_quanta","I56";
;
LOCATION"C1504"
$SEC"1"
CDS_SEC"1"
PACK_TYPE"C0402"
VOLTAGE"16V"
VALUE"0.1UF"
TOLERANCE"10%"
MATERIAL"X7R"
CDS_LIB"pure_quanta"
PART_NUMBER"CH4103K1B08";
"B"
$PN"2"16;
"A"
$PN"1"34;
%"Q_CAP"
"1","(-3975,2400)","0","pure_quanta","I62";
;
LOCATION"C1506"
$SEC"1"
CDS_SEC"1"
MATERIAL"X7R"
TOLERANCE"10%"
VOLTAGE"16V"
VALUE"0.1UF"
PACK_TYPE"C0402"
CDS_LIB"pure_quanta"
PART_NUMBER"CH4103K1B08";
"B"
$PN"2"17;
"A"
$PN"1"32;
%"GND"
"1","(-3975,2225)","0","pure_quanta_power","I63";
;
CDS_LIB"pure_quanta_power"
SIZE"1B"
HDL_POWER"GND";
"A<SIZE-1..0>\NAC"17;
%"Q_RES"
"1","(-1675,4225)","0","pure_quanta","I7";
;
LOCATION"R1633"
$SEC"1"
CDS_SEC"1"
TOLERANCE"5%"
VALUE"0"
CDS_LIB"pure_quanta"
WATTAGE"1/16W"
MATERIAL"CHIP"
PACK_TYPE"0402LF"
PART_NUMBER"CS00002JB13";
"B"
$PN"2"46;
"A"
$PN"1"45;
%"UNIVERSAL_POWER"
"1","(-6425,3725)","0","pure_quanta_power","I71";
;
HDL_POWER"PVDD18_S5_P0"
CDS_LIB"pure_quanta_power";
"A"18;
%"UNIVERSAL_POWER"
"1","(-6450,3000)","0","pure_quanta_power","I73";
;
HDL_POWER"PVDD18_S5_P0"
CDS_LIB"pure_quanta_power";
"A"35;
%"Q_CAP"
"1","(-6325,2725)","0","pure_quanta","I74";
;
LOCATION"C1505"
$SEC"1"
CDS_SEC"1"
VALUE"0.1UF"
PACK_TYPE"C0402"
VOLTAGE"16V"
TOLERANCE"10%"
MATERIAL"X7R"
CDS_LIB"pure_quanta"
PART_NUMBER"CH4103K1B08";
"B"
$PN"2"19;
"A"
$PN"1"35;
%"GND"
"1","(-6325,2500)","0","pure_quanta_power","I75";
;
CDS_LIB"pure_quanta_power"
SIZE"1B"
HDL_POWER"GND";
"A<SIZE-1..0>\NAC"19;
%"SN74AVC2T245RSWR"
"1","(-7025,4000)","2","pure_quanta","I76";
;
LOCATION"U146"
$SEC"1"
CDS_SEC"1"
VALUE"SN74AVC2T245RSWR"
MATERIAL"IC"
PART_TYPE"SMLF"
NEEDS_NO_SIZE"TRUE"
CDS_LIB"pure_quanta"
CDS_LMAN_SYM_OUTLINE"-250,375,250,-375"
PART_NUMBER"AL02T245000";
"DIR1"
$PN"10"34;
"A2"
$PN"9"61;
"A1"
$PN"8"57;
"VCCA"
$PN"7"34;
"VCCB"
$PN"6"34;
"B1"
$PN"5"85;
"B2"
$PN"4"84;
"GND"
$PN"3"36;
"OE_# \B"
$PN"2"87;
"DIR2"
$PN"1"36;
%"GND"
"1","(-7650,3575)","0","pure_quanta_power","I77";
;
CDS_LIB"pure_quanta_power"
SIZE"1B"
HDL_POWER"GND";
"A<SIZE-1..0>\NAC"36;
%"UNIVERSAL_POWER"
"1","(-7625,3125)","0","pure_quanta_power","I78";
;
HDL_POWER"P3V3_AUX"
CDS_LIB"pure_quanta_power";
"A"37;
%"Q_RES"
"1","(-1675,4125)","0","pure_quanta","I8";
;
LOCATION"R1635"
$SEC"1"
CDS_SEC"1"
TOLERANCE"1%"
VALUE"22"
CDS_LIB"pure_quanta"
WATTAGE"1/16W"
MATERIAL"CHIP"
PACK_TYPE"0402LF"
PART_NUMBER"CS02202FB02";
"B"
$PN"2"76;
"A"
$PN"1"77;
%"Q_CAP"
"1","(-7625,2800)","0","pure_quanta","I80";
;
LOCATION"C1503"
$SEC"1"
CDS_SEC"1"
PACK_TYPE"C0402"
VOLTAGE"16V"
TOLERANCE"10%"
MATERIAL"X7R"
VALUE"0.1UF"
CDS_LIB"pure_quanta"
PART_NUMBER"CH4103K1B08";
"B"
$PN"2"20;
"A"
$PN"1"37;
%"GND"
"1","(-7625,2600)","0","pure_quanta_power","I81";
;
CDS_LIB"pure_quanta_power"
SIZE"1B"
HDL_POWER"GND";
"A<SIZE-1..0>\NAC"20;
%"UNIVERSAL_POWER"
"1","(-7475,1400)","0","pure_quanta_power","I82";
;
HDL_POWER"P3V3_AUX"
CDS_LIB"pure_quanta_power";
"A"21;
%"Q_RES"
"2","(-7475,1200)","0","pure_quanta","I83";
;
LOCATION"R1622"
$SEC"1"
CDS_SEC"1"
VALUE"4.7K"
MATERIAL"CHIP"
TOLERANCE"5%"
WATTAGE"1/16W"
PACK_TYPE"0402LF"
CDS_LIB"pure_quanta"
PART_NUMBER"CS24702JB10";
"A"
$PN"1"21;
"B"
$PN"2"83;
%"GND"
"1","(-7750,1675)","0","pure_quanta_power","I84";
;
SIZE"1B"
CDS_LIB"pure_quanta_power"
HDL_POWER"GND";
"A<SIZE-1..0>\NAC"38;
%"GND"
"1","(-7475,300)","0","pure_quanta_power","I85";
;
SIZE"1B"
CDS_LIB"pure_quanta_power"
HDL_POWER"GND";
"A<SIZE-1..0>\NAC"22;
%"Q_RES"
"1","(-1675,4075)","0","pure_quanta","I9";
;
LOCATION"R1636"
$SEC"1"
CDS_SEC"1"
TOLERANCE"1%"
VALUE"22"
CDS_LIB"pure_quanta"
WATTAGE"1/16W"
MATERIAL"CHIP"
PACK_TYPE"0402LF"
PART_NUMBER"CS02202FB02";
"B"
$PN"2"78;
"A"
$PN"1"79;
%"Q_RES"
"1","(-8325,3350)","0","pure_quanta","I92";
;
LOCATION"R1619"
$SEC"1"
CDS_SEC"1"
VALUE"0"
MATERIAL"CHIP"
PACK_TYPE"0402LF"
TOLERANCE"5%"
WATTAGE"1/16W"
CDS_LIB"pure_quanta"
PART_NUMBER"CS00002JB13";
"B"
$PN"2"87;
"A"
$PN"1"86;
%"Q_RES"
"1","(-1675,4175)","0","pure_quanta","I96";
;
LOCATION"R1634"
$SEC"1"
CDS_SEC"1"
TOLERANCE"5%"
VALUE"0"
CDS_LIB"pure_quanta"
WATTAGE"1/16W"
MATERIAL"CHIP"
PACK_TYPE"0402LF"
PART_NUMBER"CS00002JB13";
"B"
$PN"2"48;
"A"
$PN"1"47;
END.
